FILE_TYPE = MULTI_PHYS_TABLE;

PART 'Q_FUSE'

{========================================================================================}
:PACK_TYPE | VALUE        | MATERIAL | PART_NUMBER                  = STANDARD | LIFECYCLE  | PART_NUMBER              | JEDEC_TYPE     | CLASS | DESCRIPTION                                    | COMPONENT_TYPE | LEAD_LENGTH | LPID | DAY        ;
{===============================================================   ========================================}
 'SMLF'    | '1.1A'       | 'IC'     | 'TMP_QDK110TPU110'(!)        = ''       | ''         | 'DK110TPU110'            | 'F1812'      | 'IC'  | '1.1A'                                        | 'CHIP'         | ''          | ''   | ''        
 'SMLF'    | '1.1A'       | 'EMPTY'  | 'TMP_QDK110TPU110'(!)        = ''       | ''         | 'DK110TPU110'            | 'F1812'      | 'IO'  | '1.1A'                                        | 'CHIP'         | ''          | ''   | ''        
 'SMLF'    | '4.5A'       | 'IC'     | 'TMP_QDK450WFU004'(!)        = ''       | ''         | 'DK450WFU004'            | 'F1206'      | 'IC'  | '4.5A'                                        | 'CHIP'         | ''          | ''   | ''        
 'SMLF'    | '4.5A'       | 'EMPTY'  | 'TMP_QDK450WFU004'(!)        = ''       | ''         | 'DK450WFU004'            | 'F1206'      | 'IO'  | '4.5A'                                        | 'CHIP'         | ''          | ''   | ''        
 'SMLF'    | '3A'         | 'IC'     | 'TMP_QDK300UFU000'(!)        = ''       | ''         | 'DK300UFU000'            | 'F1206'      | 'IC'  | '3A'                                          | 'CHIP'         | ''          | ''   | ''        
 'SMLF'    | '3A'         | 'EMPTY'  | 'TMP_QDK300UFU000'(!)        = ''       | ''         | 'DK300UFU000'            | 'F1206'      | 'IO'  | '3A'                                          | 'CHIP'         | ''          | ''   | ''        
 'SMLF'    | '5A/32V'     | 'IC'     | 'TMP_QDK500WFU011'(!)        = ''       | ''         | 'DK500WFU011'            | 'F1206'      | 'IC'  | 'FUSE SMD 5A/ 32V/3216(FAST,UL/CSA)'          | 'CHIP'         | ''          | ''   | ''        
 'SMLF'    | '5A/32V'     | 'EMPTY'  | 'TMP_QDK500WFU011'(!)        = ''       | ''         | 'DK500WFU011'            | 'F1206'      | 'IO'  | 'FUSE SMD 5A/ 32V/3216(FAST,UL/CSA)'          | 'CHIP'         | ''          | ''   | ''        
 'SMLF'    | '1.5A/63V'   | 'IC'     | 'TMP-C_S2I_0911_MASON_1'(!)  = ''       | ''         | 'TMP-C_S2I_0911_MASON_1' | 'F1206'      | 'IC'  | 'FUSE SMD 1.5A 63V FAST(TR/3216FF1.5-R)'      | 'CHIP'         | ''          | ''   | ''        
 'SMLF'    | '1.5A/63V'   | 'EMPTY'  | 'TMP-C_S2I_0911_MASON_1'(!)  = ''       | ''         | 'TMP-C_S2I_0911_MASON_1' | 'F1206'      | 'IO'  | 'FUSE SMD 1.5A 63V FAST(TR/3216FF1.5-R)'      | 'CHIP'         | ''          | ''   | ''        
 'SMLF'    | '1.6A/9V'    | 'IC'     | 'TMP_QDK160TPU113'(!)        = ''       | ''         | 'DK160TPU113'            | 'F1812'      | 'IC'  | 'FUSE SMD 1.6A 9V POLY(MINISMDC160F-2)'       | 'CHIP'         | ''          | ''   | ''        
 'SMLF'    | '1.6A/9V'    | 'EMPTY'  | 'TMP_QDK160TPU113'(!)        = ''       | ''         | 'DK160TPU113'            | 'F1812'      | 'IO'  | 'FUSE SMD 1.6A 9V POLY(MINISMDC160F-2)'       | 'CHIP'         | ''          | ''   | ''        
 'SMLF'    | '1.5A/6V'    | 'IC'     | 'QN-DK150TPU030'(!)          = ''       | ''         | 'DK150TPU030'            | 'F1206_H56'    | 'IC'  | 'FUSE SMD 1.5A,6V(POLY,NANOSMDC150F-2)'      | 'CHIP'         | ''          | ''   | ''        
 'SMLF'    | '1.5A/6V'    | 'EMPTY'  | 'QN-DK150TPU030'(!)          = ''       | ''         | 'DK150TPU030'            | 'F1206_H56'    | 'IO'  | 'FUSE SMD 1.5A,6V(POLY,NANOSMDC150F-2)'      | 'CHIP'         | ''          | ''   | ''        
 'SMLF'    | '3A/6V'      | 'IC'     | 'TMP-C_S2I_0421_MASON_1'(!)  = ''       | ''         | 'TMP-C_S2I_0421_MASON_1' | 'F2920_3'    | 'IC'  | 'FUSE SMD 3A 6V POLY(SMD300F,UL/CSA)'         | 'CHIP'         | ''          | ''   | ''        
 'SMLF'    | '3A/6V'      | 'EMPTY'  | 'TMP-C_S2I_0421_MASON_1'(!)  = ''       | ''         | 'TMP-C_S2I_0421_MASON_1' | 'F2920_3'    | 'IO'  | 'FUSE SMD 3A 6V POLY(SMD300F,UL/CSA)'         | 'CHIP'         | ''          | ''   | ''        
 'SMLF'    | '1.5A/6V'    | 'IC'     | 'TMP-C_S2I_0422_MASON_1'(!)  = ''       | ''         | 'TMP-C_S2I_0422_MASON_1' | 'F1206'      | 'IC'  | 'FUSE SMD 1.5A 6V POLY(nanoSMDC150F,UL/CSA)'  | 'CHIP'         | ''          | ''   | ''        
 'SMLF'    | '1.5A/6V'    | 'EMPTY'  | 'TMP-C_S2I_0422_MASON_1'(!)  = ''       | ''         | 'TMP-C_S2I_0422_MASON_1' | 'F1206'      | 'IO'  | 'FUSE SMD 1.5A 6V POLY(nanoSMDC150F,UL/CSA)'  | 'CHIP'         | ''          | ''   | ''        
 'SMLF'    | '0.5A/13.2V' | 'IC'     | 'TMP_QDK050SPU017'(!)        = ''       | ''         | 'DK050SPU017'            | 'F1206'      | 'IC'  | 'FUSE SMD 0.5A,13.2V(POLY,NANOSMDC050F)'      | 'CHIP'         | ''          | ''   | ''        
 'SMLF'    | '0.5A/13.2V' | 'EMPTY'  | 'TMP_QDK050SPU017'(!)        = ''       | ''         | 'DK050SPU017'            | 'F1206'      | 'IO'  | 'FUSE SMD 0.5A,13.2V(POLY,NANOSMDC050F)'      | 'CHIP'         | ''          | ''   | ''        
 'SMLF'    | '3A/15V'     | 'IC'     | 'TMP-C_S2I_0427_MASON_1'(!)  = ''       | ''         | 'TMP-C_S2I_0427_MASON_1' | 'F2920_1-25' | 'IC'  | 'FUSE SMD 3A 15V POLY(2920L300/15)'           | 'CHIP'         | ''          | ''   | ''        
 'SMLF'    | '3A/15V'     | 'EMPTY'  | 'TMP-C_S2I_0427_MASON_1'(!)  = ''       | ''         | 'TMP-C_S2I_0427_MASON_1' | 'F2920_1-25' | 'IO'  | 'FUSE SMD 3A 15V POLY(2920L300/15)'           | 'CHIP'         | ''          | ''   | ''        
 'SMLF'    | '1.5A 32V'   | 'IC'     | 'TMP_QDK150WFU000'(!)        = ''       | ''         | 'DK150WFU000'            | 'F0603_H19'  | 'IC'  | 'FUSE SMD 1.5A 32V(FAST,UL/CSA,0603)'         | 'CHIP'         | ''          | ''   | ''        
 'SMLF'    | '1.5A 32V'   | 'EMPTY'  | 'TMP_QDK150WFU000'(!)        = ''       | ''         | 'DK150WFU000'            | 'F0603_H19'  | 'IO'  | 'FUSE SMD 1.5A 32V(FAST,UL/CSA,0603)'         | 'CHIP'         | ''          | ''   | ''        
 'SMLF'    | '6A,24V'     | 'IC'     | 'TMP_QDK600VPU004'(!)        = ''       | ''         | 'DK600VPU004'            | 'F1206'      | 'IC'  | 'FUSE SMD 6A,24V POLY(1206SFS600F/24-2)'      | 'CHIP'         | ''          | ''   | ''        
 'SMLF'    | '6A,24V'     | 'EMPTY'  | 'TMP_QDK600VPU004'(!)        = ''       | ''         | 'DK600VPU004'            | 'F1206'      | 'IO'  | 'FUSE SMD 6A,24V POLY(1206SFS600F/24-2)'      | 'CHIP'         | ''          | ''   | ''        
 'SMLF'    | '10A/125V'   | 'IC'     | 'TMP_QDKA00XFU409'(!)        = ''       | ''         | 'DKA00XFU409'            | 'F2410'      | 'IC'  | 'FUSE SMD 10A/125V(FAST,UL/CSA)'              | 'CHIP'         | ''          | ''   | ''        
 'SMLF'    | '10A/125V'   | 'EMPTY'  | 'TMP_QDKA00XFU409'(!)        = ''       | ''         | 'DKA00XFU409'            | 'F2410'      | 'IO'  | 'FUSE SMD 10A/125V(FAST,UL/CSA)'              | 'CHIP'         | ''          | ''   | ''        
 'SMLF'    | '.75A/13.2V' | 'IC'     | 'DK075SPU002'(!)             = ''       | ''         | 'DK075SPU002'            | 'F1812'      | 'IC'  | 'FUSE SMD .75A,13.2V(POLY,MINISMDC075F)LF'    | 'CHIP'         | ''          | ''   | ''        
 'SMLF'    | '.75A/13.2V' | 'EMPTY'  | 'DK075SPU002'(!)             = ''       | ''         | 'DK075SPU002'            | 'F1812'      | 'IO'  | 'FUSE SMD .75A,13.2V(POLY,MINISMDC075F)LF'    | 'CHIP'         | ''          | ''   | ''        
 'SMLF'    | '1.1A/16V'   | 'IC'     | 'DK110SPU001'(!)             = ''       | ''         | 'DK110SPU001'            | 'F1812'      | 'IC'  | 'FUSE SMD 1.1A 16V POLY(MF-MSMF110/16)'       | 'CHIP'         | ''          | ''   | ''        
 'SMLF'    | '1.1A/16V'   | 'EMPTY'  | 'DK110SPU001'(!)             = ''       | ''         | 'DK110SPU001'            | 'F1812'      | 'IO'  | 'FUSE SMD 1.1A 16V POLY(MF-MSMF110/16)'       | 'CHIP'         | ''          | ''   | ''        
 'SMLF'    | '3A/15V'     | 'IC'     | 'DK300SPU002'(!)             = ''       | ''         | 'DK300SPU002'            | 'F2920_3'    | 'IC'  | 'FUSE SMD 3A,15V,POLY(SMD300F/15)'            | 'CHIP'         | ''          | ''   | ''        
 'SMLF'    | '3A/15V'     | 'EMPTY'  | 'DK300SPU002'(!)             = ''       | ''         | 'DK300SPU002'            | 'F2920_3'    | 'IO'  | 'FUSE SMD 3A,15V,POLY(SMD300F/15)'            | 'CHIP'         | ''          | ''   | ''        
 'SMLF'    | '1.1A/8V'    | 'IC'     | 'DK110TPU012'(!)             = ''       | ''         | 'DK110TPU012'            | 'F1812'      | 'IC'  | 'FUSE SMD 1.1A,8V(POLY,MINISMDC110F-2)'       | 'CHIP'         | ''          | ''   | '20101005'
 'SMLF'    | '1.1A/8V'    | 'EMPTY'  | 'DK110TPU012'(!)             = ''       | ''         | 'DK110TPU012'            | 'F1812'      | 'IO'  | 'FUSE SMD 1.1A,8V(POLY,MINISMDC110F-2)'       | 'CHIP'         | ''          | ''   | '20101005'
 'SMLF'    | '1.5A/6V'    | 'IC'     | 'DK150TPU072'(!)             = ''       | ''         | 'DK150TPU072'            | 'F1206'      | 'IC'  | 'FUSE SMD 1.5A,6V(POLY,1206L150PR)'           | 'CHIP'         | ''          | ''   | '20110207'
 'SMLF'    | '1.5A/6V'    | 'EMPTY'  | 'DK150TPU072'(!)             = ''       | ''         | 'DK150TPU072'            | 'F1206'      | 'IO'  | 'FUSE SMD 1.5A,6V(POLY,1206L150PR)'           | 'CHIP'         | ''          | ''   | '20110207'
 'SMLF'    | '1.1A/6V'    | 'IC'     | 'DK110TPU501'(!)             = ''       | ''         | 'DK110TPU501'            | 'F1206'      | 'IC'  | 'FUSE SMD 1.1A6V POLY(NANOSMDC110F-2)1206'    | 'CHIP'         | ''          | ''   | '20110217'
 'SMLF'    | '1.1A/6V'    | 'EMPTY'  | 'DK110TPU501'(!)             = ''       | ''         | 'DK110TPU501'            | 'F1206'      | 'IO'  | 'FUSE SMD 1.1A6V POLY(NANOSMDC110F-2)1206'    | 'CHIP'         | ''          | ''   | '20110217'
 'SMLF'    | '5A/125V'    | 'IC'     | 'DK500XFU001'(!)             = ''       | ''         | 'DK500XFU001'            | 'F2410'      | 'IC'  | 'FUSE SMD 5A/125V(FAST,UL/CSA)0451005.MRL'    | 'CHIP'         | ''          | ''   | '20120224'
 'SMLF'    | '5A/125V'    | 'EMPTY'  | 'DK500XFU001'(!)             = ''       | ''         | 'DK500XFU001'            | 'F2410'      | 'IO'  | 'FUSE SMD 5A/125V(FAST,UL/CSA)0451005.MRL'    | 'CHIP'         | ''          | ''   | '20120224'
 'SMLF'    | '3A/15V'     | 'IC'     | 'DK300SPU000'(!)             = ''       | ''         | 'DK300SPU000'            | 'F2920_1-25' | 'IC'  | 'FUSE SMD 3A 15V POLY(2920L300/15DR)'         | 'CHIP'         | ''          | ''   | '20120306'
 'SMLF'    | '3A/15V'     | 'EMPTY'  | 'DK300SPU000'(!)             = ''       | ''         | 'DK300SPU000'            | 'F2920_1-25' | 'IO'  | 'FUSE SMD 3A 15V POLY(2920L300/15DR)'         | 'CHIP'         | ''          | ''   | '20120306'
 'SMLF'    | '15A/125V'   | 'IC'     | 'DKF00VFU004'(!)             = ''       | ''         | 'DKF00VFU004'            | 'F2410'      | 'IC'  | 'FUSE SMD 15A/125V(FAST,UL/CSA)SSQ 15'        | 'CHIP'         | ''          | ''   | '20120309'
 'SMLF'    | '15A/125V'   | 'EMPTY'  | 'DKF00VFU004'(!)             = ''       | ''         | 'DKF00VFU004'            | 'F2410'      | 'IO'  | 'FUSE SMD 15A/125V(FAST,UL/CSA)SSQ 15'        | 'CHIP'         | ''          | ''   | '20120309'
 'SMLF'     | '1.5A/125V'  | 'IC'     | 'DK150XFU000'(!)            = ''       | ''         | 'DK150XFU000'            | 'F2410'           | 'IC'  | 'FUSE SMD 1.5A/125V(FAST,UL/CSA/CE)SSQ1.5'   | 'CHIP'         | ''          | ''   | '20120406'
 'SMLF'     | '1.5A/125V'  | 'EMPTY'  | 'DK150XFU000'(!)            = ''       | ''         | 'DK150XFU000'            | 'F2410'           | 'IO'  | 'FUSE SMD 1.5A/125V(FAST,UL/CSA/CE)SSQ1.5'   | 'CHIP'         | ''          | ''   | '20120406'
 'SMLF'     | '2A/6V'      | 'IC'     | 'DK200TPU004'(!)            = ''       | ''         | 'DK200TPU004'            | 'F1206'           | 'IC'  | 'FUSE SMD 2A 6V(POLY,UL/CSA,1206)'           | 'CHIP'         | ''          | ''   | '20120421'
 'SMLF'     | '2A/6V'      | 'EMPTY'  | 'DK200TPU004'(!)            = ''       | ''         | 'DK200TPU004'            | 'F1206'           | 'IO'  | 'FUSE SMD 2A 6V(POLY,UL/CSA,1206)'           | 'CHIP'         | ''          | ''   | '20120421'
 'THLF'    | '9A/16V'     | 'IC'     | 'DK900SPU001'(!)             = ''       | ''         | 'DK900SPU001'            | 'F1255_16R900GMR'   | 'IC'  | 'FUSE DIP 9A/16V (POLY,UL/TUV)16R900GMR'     | 'CHIP'         | ''          | ''   | '20120314'
 'THLF'    | '9A/16V'     | 'EMPTY'  | 'DK900SPU001'(!)             = ''       | ''         | 'DK900SPU001'            | 'F1255_16R900GMR'   | 'IO'  | 'FUSE DIP 9A/16V (POLY,UL/TUV)16R900GMR'     | 'CHIP'         | ''          | ''   | '20120314'
 'THLF'    | '14A/16V'    | 'IC'     | 'DKE00SPU000'(!)             = ''       | ''         | 'DKE00SPU000'            | 'F9314_16R1400GH'   | 'IC'  | 'FUSE DIP 14A/16V(POLY,UL/TUV)16R1400GH'     | 'CHIP'         | ''          | ''   | '20120314'
 'THLF'    | '14A/16V'    | 'EMPTY'  | 'DKE00SPU000'(!)             = ''       | ''         | 'DKE00SPU000'            | 'F9314_16R1400GH'   | 'IO'  | 'FUSE DIP 14A/16V(POLY,UL/TUV)16R1400GH'     | 'CHIP'         | ''          | ''   | '20120314'
 'THLF_SEL'    | '9A/16V'     | 'IC'     | 'SP_DK900SPU001'(!)      = ''       | ''         | 'SP_DK900SPU001'         | 'G_F1255_16R900GMR' | 'IC'  | 'FUSE DIP 9A/16V (POLY,UL/TUV)16R900GMR'     | 'CHIP'         | ''          | ''   | '20120314'
 'THLF_SEL'    | '9A/16V'     | 'EMPTY'  | 'SP_DK900SPU001'(!)      = ''       | ''         | 'SP_DK900SPU001'         | 'G_F1255_16R900GMR' | 'IO'  | 'FUSE DIP 9A/16V (POLY,UL/TUV)16R900GMR'     | 'CHIP'         | ''          | ''   | '20120314'
 'THLF_SEL'    | '14A/16V'    | 'IC'     | 'SP_DKE00SPU000'(!)      = ''       | ''         | 'SP_DKE00SPU000'         | 'G_F9314_16R1400GH' | 'IC'  | 'FUSE DIP 14A/16V(POLY,UL/TUV)16R1400GH'     | 'CHIP'         | ''          | ''   | '20120314'
 'THLF_SEL'    | '14A/16V'    | 'EMPTY'  | 'SP_DKE00SPU000'(!)      = ''       | ''         | 'SP_DKE00SPU000'         | 'G_F9314_16R1400GH' | 'IO'  | 'FUSE DIP 14A/16V(POLY,UL/TUV)16R1400GH'     | 'CHIP'         | ''          | ''   | '20120314'
 'SMLF'     | '0.5A'       | 'IC'     | 'DK050SPU033'(!)            = ''       | ''         | 'DK050SPU033'            | 'F1812'           | 'IC'  | 'FUSE SMD 0.5A 15V POLY(SMD1812P050TF)'      | 'CHIP'         | ''          | ''   | '20120525'
 'SMLF'     | '0.5A'       | 'EMPTY'  | 'DK050SPU033'(!)            = ''       | ''         | 'DK050SPU033'            | 'F1812'           | 'IO'  | 'FUSE SMD 0.5A 15V POLY(SMD1812P050TF)'      | 'CHIP'         | ''          | ''   | '20120525'
 'SMLF'     | '2.6A'       | 'IC'     | 'DK260TPU001'(!)            = ''       | ''         | 'DK260TPU001'            | 'F1812'           | 'IC'  | 'FUSE SMD 2.6A,6V(POLY,MINISMDC260F)'        | 'CHIP'         | ''          | ''   | '20120627'
 'SMLF'     | '2.6A'       | 'EMPTY'  | 'DK260TPU001'(!)            = ''       | ''         | 'DK260TPU001'            | 'F1812'           | 'IO'  | 'FUSE SMD 2.6A,6V(POLY,MINISMDC260F)'        | 'CHIP'         | ''          | ''   | '20120627'
 'SMLF'     | '8A/32V'     | 'IC'     | 'DK800WFU000'(!)            = ''       | ''         | 'DK800WFU000'            | 'F1206'             | 'IC'  | 'FUSE SMD 8A 32V(FAST,0437008.WR,1206)'      | 'CHIP'         | ''          | ''   | '20120628'
 'SMLF'     | '8A/32V'     | 'EMPTY'  | 'DK800WFU000'(!)            = ''       | ''         | 'DK800WFU000'            | 'F1206'             | 'IO'  | 'FUSE SMD 8A 32V(FAST,0437008.WR,1206)'      | 'CHIP'         | ''          | ''   | '20120628'
 'SMLF'     | '3A/24V'     | 'IC'     | 'DK300VPU000'(!)            = ''       | ''         | 'DK300VPU000'            | 'F2920_1-6'       | 'IC'  | 'FUSE SMD 3A 24V POLY(MF-LSMF300/24X-2)'     | 'CHIP'         | ''          | ''   | '20120706'
 'SMLF'     | '3A/24V'     | 'EMPTY'  | 'DK300VPU000'(!)            = ''       | ''         | 'DK300VPU000'            | 'F2920_1-6'       | 'IO'  | 'FUSE SMD 3A 24V POLY(MF-LSMF300/24X-2)'     | 'CHIP'         | ''          | ''   | '20120706'
 'SMLF'     | '0.35A/6V'   | 'IC'     | 'DK035TPU000'(!)            = ''       | ''         | 'DK035TPU000'            | 'F0603_H62'       | 'IC'  | 'FUSE SMD 0.35A.6V(POLY.SMD0603P035TF)'      | 'CHIP'         | ''          | ''   | '20120914'
 'SMLF'     | '0.35A/6V'   | 'EMPTY'  | 'DK035TPU000'(!)            = ''       | ''         | 'DK035TPU000'            | 'F0603_H62'       | 'IO'  | 'FUSE SMD 0.35A.6V(POLY.SMD0603P035TF)'      | 'CHIP'         | ''          | ''   | '20120914'

END_PART

END.

